FILE_TYPE = CONNECTIVITY;
{Allegro Design Entry HDL 16.6-p007 (v16-6-112F) 10/10/2012}
"PAGE_NUMBER" = 69;
0"NC";
1"GND\g";
2"TP_CPU1_UPI2_RSVD_CC12";
3"TP_CPU1_UPI2_RSVD_CC10";
4"TP_CPU1_UPI2_RSVD_CE12";
5"TP_CPU1_UPI2_RSVD_CH11";
6"TP_CPU1_UPI2_RSVD_CF13";
7"TP_CPU1_UPI2_RSVD_CJ14";
8"TP_CPU1_UPI2_RSVD_CM13";
9"TP_CPU1_UPI2_RSVD_CA12";
10"TP_CPU1_UPI2_RSVD_CB11";
11"TP_CPU1_UPI2_RSVD_CD11";
12"TP_CPU1_UPI2_RSVD_CF11";
13"TP_CPU1_UPI2_RSVD_CG12";
14"TP_CPU1_UPI2_RSVD_CH13";
15"TP_CPU1_UPI2_RSVD_CK13";
16"TP_CPU1_UPI2_RSVD_CR14";
17"TP_CPU1_UPI2_RSVD_CV13";
18"TP_CPU1_UPI2_RSVD_CW16";
19"TP_CPU1_UPI2_RSVD_DB15";
20"TP_CPU1_UPI2_RSVD_DD15";
21"TP_CPU1_UPI2_RSVD_DE16";
22"TP_CPU1_UPI2_RSVD_DF17";
23"TP_CPU1_UPI2_RSVD_DH17";
24"TP_CPU1_UPI2_RSVD_DJ18";
25"TP_CPU1_UPI2_RSVD_DJ20";
26"TP_CPU1_UPI2_RSVD_DK19";
27"TP_CPU1_UPI2_RSVD_DN20";
28"TP_CPU1_UPI2_RSVD_DP21";
29"TP_CPU1_UPI2_RSVD_CU14";
30"TP_CPU1_UPI2_RSVD_CW14";
31"TP_CPU1_UPI2_RSVD_DA16";
32"TP_CPU1_UPI2_RSVD_DC16";
33"TP_CPU1_UPI2_RSVD_DF15";
34"TP_CPU1_UPI2_RSVD_DD17";
35"TP_CPU1_UPI2_RSVD_DG18";
36"TP_CPU1_UPI2_RSVD_DK17";
37"TP_CPU1_UPI2_RSVD_DH19";
38"TP_CPU1_UPI2_RSVD_DG20";
39"TP_CPU1_UPI2_RSVD_DL20";
40"TP_CPU1_UPI2_RSVD_DM21";
41"TP_CPU1_UPI2_RSVD_DT21";
%"SKX_EXT_B"
"15","(-4275,2700)","0","chpset_lib","I1";
;
CDS_SEC"15"
CDS_LOCATION"U2D1"
SEC"15"
CDS_LIB"chpset_lib"
SEC_TYPE"BGA1"
PACK_TYPE"BGA1"
MATERIAL"IC"
PART_NUMBER"TBD"
LOCATION"U2D1";
"UPI2_TX_DP<0>"
$PN"DP21"9;
"UPI2_TX_DP<1>"
$PN"DN20"10;
"UPI2_TX_DP<2>"
$PN"DK19"11;
"UPI2_TX_DP<3>"
$PN"DJ20"12;
"UPI2_TX_DP<4>"
$PN"DJ18"13;
"UPI2_TX_DP<5>"
$PN"DH17"14;
"UPI2_TX_DP<6>"
$PN"DF17"15;
"UPI2_TX_DP<7>"
$PN"DE16"16;
"UPI2_TX_DP<8>"
$PN"DD15"17;
"UPI2_TX_DP<9>"
$PN"DB15"18;
"UPI2_TX_DP<10>"
$PN"CW16"19;
"UPI2_TX_DP<11>"
$PN"CV13"20;
"UPI2_TX_DP<12>"
$PN"CR14"21;
"UPI2_TX_DP<13>"
$PN"CK13"22;
"UPI2_TX_DP<14>"
$PN"CH13"23;
"UPI2_TX_DP<15>"
$PN"CG12"24;
"UPI2_TX_DP<16>"
$PN"CF11"25;
"UPI2_TX_DP<17>"
$PN"CD11"26;
"UPI2_TX_DP<18>"
$PN"CB11"27;
"UPI2_TX_DP<19>"
$PN"CA12"28;
"UPI2_TX_DN<0>"
$PN"DT21"2;
"UPI2_TX_DN<1>"
$PN"DM21"3;
"UPI2_TX_DN<2>"
$PN"DL20"4;
"UPI2_TX_DN<3>"
$PN"DG20"5;
"UPI2_TX_DN<4>"
$PN"DH19"6;
"UPI2_TX_DN<5>"
$PN"DK17"7;
"UPI2_TX_DN<6>"
$PN"DG18"8;
"UPI2_TX_DN<7>"
$PN"DD17"29;
"UPI2_TX_DN<8>"
$PN"DF15"30;
"UPI2_TX_DN<9>"
$PN"DC16"31;
"UPI2_TX_DN<10>"
$PN"DA16"32;
"UPI2_TX_DN<11>"
$PN"CW14"33;
"UPI2_TX_DN<12>"
$PN"CU14"34;
"UPI2_TX_DN<13>"
$PN"CM13"35;
"UPI2_TX_DN<14>"
$PN"CJ14"36;
"UPI2_TX_DN<15>"
$PN"CF13"37;
"UPI2_TX_DN<16>"
$PN"CH11"38;
"UPI2_TX_DN<17>"
$PN"CE12"39;
"UPI2_TX_DN<18>"
$PN"CC10"40;
"UPI2_TX_DN<19>"
$PN"CC12"41;
"UPI2_RX_DP<0>"
$PN"DG22"1;
"UPI2_RX_DP<1>"
$PN"DD21"1;
"UPI2_RX_DP<2>"
$PN"DA22"1;
"UPI2_RX_DP<3>"
$PN"DC20"1;
"UPI2_RX_DP<4>"
$PN"DB19"1;
"UPI2_RX_DP<5>"
$PN"CY19"1;
"UPI2_RX_DP<6>"
$PN"CU20"1;
"UPI2_RX_DP<7>"
$PN"CW18"1;
"UPI2_RX_DP<8>"
$PN"CR20"1;
"UPI2_RX_DP<9>"
$PN"CN18"1;
"UPI2_RX_DP<10>"
$PN"CP19"1;
"UPI2_RX_DP<11>"
$PN"CM21"1;
"UPI2_RX_DP<12>"
$PN"CJ16"1;
"UPI2_RX_DP<13>"
$PN"CK17"1;
"UPI2_RX_DP<14>"
$PN"CG16"1;
"UPI2_RX_DP<15>"
$PN"CF15"1;
"UPI2_RX_DP<16>"
$PN"CC14"1;
"UPI2_RX_DP<17>"
$PN"CD17"1;
"UPI2_RX_DP<18>"
$PN"BY15"1;
"UPI2_RX_DP<19>"
$PN"CA16"1;
"UPI2_RX_DN<0>"
$PN"DF23"1;
"UPI2_RX_DN<1>"
$PN"DE22"1;
"UPI2_RX_DN<2>"
$PN"DC22"1;
"UPI2_RX_DN<3>"
$PN"DB21"1;
"UPI2_RX_DN<4>"
$PN"DD19"1;
"UPI2_RX_DN<5>"
$PN"DA20"1;
"UPI2_RX_DN<6>"
$PN"CW20"1;
"UPI2_RX_DN<7>"
$PN"CV19"1;
"UPI2_RX_DN<8>"
$PN"CT21"1;
"UPI2_RX_DN<9>"
$PN"CR18"1;
"UPI2_RX_DN<10>"
$PN"CN20"1;
"UPI2_RX_DN<11>"
$PN"CP21"1;
"UPI2_RX_DN<12>"
$PN"CL16"1;
"UPI2_RX_DN<13>"
$PN"CJ18"1;
"UPI2_RX_DN<14>"
$PN"CH17"1;
"UPI2_RX_DN<15>"
$PN"CE16"1;
"UPI2_RX_DN<16>"
$PN"CD15"1;
"UPI2_RX_DN<17>"
$PN"CF17"1;
"UPI2_RX_DN<18>"
$PN"CB15"1;
"UPI2_RX_DN<19>"
$PN"BY17"1;
%"GND"
"1","(-6025,1475)","0","mstr_symbols","I2";
;
HDL_POWER"GND"
BODY_TYPE"PLUMBING"
CDS_LIB"mstr_symbols"
SIZE"1B"
VOLTAGE"0.0V";
"A\NAC"1;
END.
